(kicad_pcb
	(version 20221018)
	(generator pcbnew)
	(general
    (thickness 1.62)
  )
	(paper "A4")
	(title_block
    (title "ECP5 - Datacenter Secure Control Module (DC-SCM)")
    (date "2024-07-01")
    (rev "1.2.1")
		(comment 9 "footprints 483-490 of 506")
	)
	(layers
    (0 "F.Cu" signal)
    (1 "In1.Cu" power)
    (2 "In2.Cu" signal)
    (3 "In3.Cu" power)
    (4 "In4.Cu" power)
    (5 "In5.Cu" signal)
    (6 "In6.Cu" power)
    (31 "B.Cu" signal)
    (32 "B.Adhes" user "B.Adhesive")
    (33 "F.Adhes" user "F.Adhesive")
    (34 "B.Paste" user)
    (35 "F.Paste" user)
    (36 "B.SilkS" user "B.Silkscreen")
    (37 "F.SilkS" user "F.Silkscreen")
    (38 "B.Mask" user)
    (39 "F.Mask" user)
    (40 "Dwgs.User" user "User.Drawings")
    (41 "Cmts.User" user "User.Comments")
    (42 "Eco1.User" user "User.Eco1")
    (43 "Eco2.User" user "User.Eco2")
    (44 "Edge.Cuts" user)
    (45 "Margin" user)
    (46 "B.CrtYd" user "B.Courtyard")
    (47 "F.CrtYd" user "F.Courtyard")
    (48 "B.Fab" user)
    (49 "F.Fab" user)
  )
	(footprint "antmicro-footprints:R_0402_1005Metric" (layer "B.Cu")
    (at 139.75 83.64 -90)
    (descr "Resistor SMD 0402")
    (tags "resistor SMD 0402")
    (property "Author" "Antmicro")
    (property "License" "Apache-2.0")
    (property "MPN" "CR0402-FX-4701GLF")
    (property "Manufacturer" "Bourns")
    (property "Public" "False")
    (property "Sheetfile" "interfaces.kicad_sch")
    (property "Sheetname" "Interfaces")
    (property "Tolerance" "1%")
    (property "Val" "4k7")
    (property "ki_description" "SMD Chip Resistor, 4.7 kohm, ± 1%, 62.5 mW, 0402 [1005 Metric], Thick Film, General Purpose")
    (property "ki_keywords" "0402, SMT, RESISTOR, PASSIVE")
    (attr smd)
    (fp_text reference "R150" (at -2.516667 -0.01 90) (layer "B.SilkS")
        (effects (font (size 0.7 0.7) (thickness 0.15)) (justify mirror))
    )
    (fp_text value "R_4k7_0402" (at 0 -1.17 90) (layer "B.Fab")
        (effects (font (size 1 1) (thickness 0.15)) (justify mirror))
    )
    (fp_text user "${REFERENCE}" (at 0 0 90) (layer "B.Fab")
        (effects (font (size 0.25 0.25) (thickness 0.04)) (justify mirror))
    )
    (fp_text user "License: Apache-2.0" (at -0.95 -5.169 90) (layer "B.Fab") hide
        (effects (font (size 0.7 0.7) (thickness 0.15)) (justify left bottom mirror))
    )
    (fp_text user "Author: Antmicro" (at -0.95 -4.169 90) (layer "B.Fab") hide
        (effects (font (size 0.7 0.7) (thickness 0.15)) (justify left bottom mirror))
    )
    (fp_rect (start -0.925 0.47) (end 0.925 -0.47)
      (stroke (width 0.05) (type default)) (fill none) (layer "B.CrtYd"))
    (fp_rect (start -0.5 0.25) (end 0.5 -0.25)
      (stroke (width 0.15) (type solid)) (fill none) (layer "B.Fab"))
    (pad "1" smd roundrect (at -0.48 0 270) (size 0.59 0.64) (layers "B.Cu" "B.Paste" "B.Mask") (roundrect_rratio 0.25)
      (net 415 "VBUS") (pintype "passive"))
    (pad "2" smd roundrect (at 0.48 0 270) (size 0.59 0.64) (layers "B.Cu" "B.Paste" "B.Mask") (roundrect_rratio 0.25)
      (net 434 "Net-(U14-DDBUS7)") (pintype "passive"))
  )
	(footprint "antmicro-footprints:R_0402_1005Metric" (layer "B.Cu")
    (at 140.45 88.375 180)
    (descr "Resistor SMD 0402")
    (tags "resistor SMD 0402")
    (property "Author" "Antmicro")
    (property "License" "Apache-2.0")
    (property "MPN" "CR0402-FX-1002GLF")
    (property "Manufacturer" "Bourns")
    (property "Public" "False")
    (property "Sheetfile" "interfaces.kicad_sch")
    (property "Sheetname" "Interfaces")
    (property "Tolerance" "1%")
    (property "Val" "10k")
    (property "ki_description" "SMD Chip Resistor, 10 kohm, ± 1%, 62.5 mW, 0402 [1005 Metric], Thick Film, General Purpose")
    (property "ki_keywords" "0402, SMT, RESISTOR, PASSIVE")
    (attr smd)
    (fp_text reference "R151" (at -2.24 -0.58 180) (layer "B.SilkS")
        (effects (font (size 0.7 0.7) (thickness 0.15)) (justify mirror))
    )
    (fp_text value "R_10k_0402" (at 0 -1.17 180) (layer "B.Fab")
        (effects (font (size 1 1) (thickness 0.15)) (justify mirror))
    )
    (fp_text user "${REFERENCE}" (at 0 0 180) (layer "B.Fab")
        (effects (font (size 0.25 0.25) (thickness 0.04)) (justify mirror))
    )
    (fp_text user "License: Apache-2.0" (at -0.95 -5.169) (layer "B.Fab") hide
        (effects (font (size 0.7 0.7) (thickness 0.15)) (justify left bottom mirror))
    )
    (fp_text user "Author: Antmicro" (at -0.95 -4.169) (layer "B.Fab") hide
        (effects (font (size 0.7 0.7) (thickness 0.15)) (justify left bottom mirror))
    )
    (fp_rect (start -0.925 0.47) (end 0.925 -0.47)
      (stroke (width 0.05) (type default)) (fill none) (layer "B.CrtYd"))
    (fp_rect (start -0.5 0.25) (end 0.5 -0.25)
      (stroke (width 0.15) (type solid)) (fill none) (layer "B.Fab"))
    (pad "1" smd roundrect (at -0.48 0 180) (size 0.59 0.64) (layers "B.Cu" "B.Paste" "B.Mask") (roundrect_rratio 0.25)
      (net 434 "Net-(U14-DDBUS7)") (pintype "passive"))
    (pad "2" smd roundrect (at 0.48 0 180) (size 0.59 0.64) (layers "B.Cu" "B.Paste" "B.Mask") (roundrect_rratio 0.25)
      (net 1 "GND") (pintype "passive"))
  )
	(footprint "antmicro-footprints:C_0402_1005Metric" (layer "B.Cu")
    (at 134.9 93.925 180)
    (descr "Capacitor SMD 0402")
    (tags "capacitor SMD 0402")
    (property "Author" "Antmicro")
    (property "Dielectric" "X5R")
    (property "License" "Apache-2.0")
    (property "MPN" "GRM155R61H104KE14D")
    (property "Manufacturer" "Murata")
    (property "Public" "False")
    (property "Sheetfile" "interfaces.kicad_sch")
    (property "Sheetname" "Interfaces")
    (property "Val" "100n")
    (property "Voltage" "50V")
    (property "ki_description" "SMD Multilayer Ceramic Capacitor, 0.1 µF, 50 V, 0402 [1005 Metric], ± 10%, X5R, GRM Series")
    (property "ki_keywords" "0402, SMT, CAPACITOR, PASSIVE, CERAMIC, MLCC")
    (attr smd)
    (fp_text reference "C255" (at 0.29 1.02) (layer "B.SilkS")
        (effects (font (size 0.7 0.7) (thickness 0.15)) (justify mirror))
    )
    (fp_text value "C_100n_0402" (at 0 -1.17) (layer "B.Fab")
        (effects (font (size 1 1) (thickness 0.15)) (justify mirror))
    )
    (fp_text user "Author: Antmicro" (at -0.939 -3.399) (layer "B.Fab") hide
        (effects (font (size 0.7 0.7) (thickness 0.15)) (justify left bottom mirror))
    )
    (fp_text user "${REFERENCE}" (at 0 0 90) (layer "B.Fab")
        (effects (font (size 0.25 0.25) (thickness 0.04)) (justify mirror))
    )
    (fp_text user "License: Apache-2.0" (at -0.939 -5.799) (layer "B.Fab") hide
        (effects (font (size 0.7 0.7) (thickness 0.15)) (justify left bottom mirror))
    )
    (fp_rect (start -0.925 0.47) (end 0.925 -0.47)
      (stroke (width 0.05) (type default)) (fill none) (layer "B.CrtYd"))
    (fp_line (start -0.494 -0.248) (end -0.494 0.25)
      (stroke (width 0.15) (type solid)) (layer "B.Fab"))
    (fp_line (start -0.494 0.25) (end 0.504 0.25)
      (stroke (width 0.15) (type solid)) (layer "B.Fab"))
    (fp_line (start 0.504 -0.248) (end -0.494 -0.248)
      (stroke (width 0.15) (type solid)) (layer "B.Fab"))
    (fp_line (start 0.504 0.25) (end 0.504 -0.248)
      (stroke (width 0.15) (type solid)) (layer "B.Fab"))
    (pad "1" smd roundrect (at -0.48 0 180) (size 0.59 0.64) (layers "B.Cu" "B.Paste" "B.Mask") (roundrect_rratio 0.25)
      (net 1 "GND") (pintype "passive"))
    (pad "2" smd roundrect (at 0.48 0 180) (size 0.59 0.64) (layers "B.Cu" "B.Paste" "B.Mask") (roundrect_rratio 0.25)
      (net 657 "VREGOUT") (pintype "passive"))
  )
	(footprint "antmicro-footprints:C_0402_1005Metric" (layer "B.Cu")
    (at 137.5 93.875 180)
    (descr "Capacitor SMD 0402")
    (tags "capacitor SMD 0402")
    (property "Author" "Antmicro")
    (property "Dielectric" "X5R")
    (property "License" "Apache-2.0")
    (property "MPN" "GRM155R61H104KE14D")
    (property "Manufacturer" "Murata")
    (property "Public" "False")
    (property "Sheetfile" "interfaces.kicad_sch")
    (property "Sheetname" "Interfaces")
    (property "Val" "100n")
    (property "Voltage" "50V")
    (property "ki_description" "SMD Multilayer Ceramic Capacitor, 0.1 µF, 50 V, 0402 [1005 Metric], ± 10%, X5R, GRM Series")
    (property "ki_keywords" "0402, SMT, CAPACITOR, PASSIVE, CERAMIC, MLCC")
    (attr smd)
    (fp_text reference "C254" (at 0.12 0.92) (layer "B.SilkS")
        (effects (font (size 0.7 0.7) (thickness 0.15)) (justify mirror))
    )
    (fp_text value "C_100n_0402" (at 0 -1.17) (layer "B.Fab")
        (effects (font (size 1 1) (thickness 0.15)) (justify mirror))
    )
    (fp_text user "License: Apache-2.0" (at -0.939 -5.799) (layer "B.Fab") hide
        (effects (font (size 0.7 0.7) (thickness 0.15)) (justify left bottom mirror))
    )
    (fp_text user "Author: Antmicro" (at -0.939 -3.399) (layer "B.Fab") hide
        (effects (font (size 0.7 0.7) (thickness 0.15)) (justify left bottom mirror))
    )
    (fp_text user "${REFERENCE}" (at 0 0) (layer "B.Fab")
        (effects (font (size 0.25 0.25) (thickness 0.04)) (justify mirror))
    )
    (fp_rect (start -0.925 0.47) (end 0.925 -0.47)
      (stroke (width 0.05) (type default)) (fill none) (layer "B.CrtYd"))
    (fp_line (start -0.494 -0.248) (end -0.494 0.25)
      (stroke (width 0.15) (type solid)) (layer "B.Fab"))
    (fp_line (start -0.494 0.25) (end 0.504 0.25)
      (stroke (width 0.15) (type solid)) (layer "B.Fab"))
    (fp_line (start 0.504 -0.248) (end -0.494 -0.248)
      (stroke (width 0.15) (type solid)) (layer "B.Fab"))
    (fp_line (start 0.504 0.25) (end 0.504 -0.248)
      (stroke (width 0.15) (type solid)) (layer "B.Fab"))
    (pad "1" smd roundrect (at -0.48 0 180) (size 0.59 0.64) (layers "B.Cu" "B.Paste" "B.Mask") (roundrect_rratio 0.25)
      (net 1 "GND") (pintype "passive"))
    (pad "2" smd roundrect (at 0.48 0 180) (size 0.59 0.64) (layers "B.Cu" "B.Paste" "B.Mask") (roundrect_rratio 0.25)
      (net 2 "VCC3V3") (pintype "passive"))
  )
	(footprint "antmicro-footprints:C_0402_1005Metric" (layer "B.Cu")
    (at 140.1 86.325 90)
    (descr "Capacitor SMD 0402")
    (tags "capacitor SMD 0402")
    (property "Author" "Antmicro")
    (property "Dielectric" "X5R")
    (property "License" "Apache-2.0")
    (property "MPN" "GRM155R61H104KE14D")
    (property "Manufacturer" "Murata")
    (property "Public" "False")
    (property "Sheetfile" "interfaces.kicad_sch")
    (property "Sheetname" "Interfaces")
    (property "Val" "100n")
    (property "Voltage" "50V")
    (property "ki_description" "SMD Multilayer Ceramic Capacitor, 0.1 µF, 50 V, 0402 [1005 Metric], ± 10%, X5R, GRM Series")
    (property "ki_keywords" "0402, SMT, CAPACITOR, PASSIVE, CERAMIC, MLCC")
    (attr smd)
    (fp_text reference "C259" (at 0.03 1.5 90) (layer "B.SilkS")
        (effects (font (size 0.7 0.7) (thickness 0.15)) (justify mirror))
    )
    (fp_text value "C_100n_0402" (at 0 -1.17 90) (layer "B.Fab")
        (effects (font (size 1 1) (thickness 0.15)) (justify mirror))
    )
    (fp_text user "${REFERENCE}" (at 0 0 90) (layer "B.Fab")
        (effects (font (size 0.25 0.25) (thickness 0.04)) (justify mirror))
    )
    (fp_text user "Author: Antmicro" (at -0.939 -3.399 270) (layer "B.Fab") hide
        (effects (font (size 0.7 0.7) (thickness 0.15)) (justify left bottom mirror))
    )
    (fp_text user "License: Apache-2.0" (at -0.939 -5.799 270) (layer "B.Fab") hide
        (effects (font (size 0.7 0.7) (thickness 0.15)) (justify left bottom mirror))
    )
    (fp_rect (start -0.925 0.47) (end 0.925 -0.47)
      (stroke (width 0.05) (type default)) (fill none) (layer "B.CrtYd"))
    (fp_line (start -0.494 -0.248) (end -0.494 0.25)
      (stroke (width 0.15) (type solid)) (layer "B.Fab"))
    (fp_line (start -0.494 0.25) (end 0.504 0.25)
      (stroke (width 0.15) (type solid)) (layer "B.Fab"))
    (fp_line (start 0.504 -0.248) (end -0.494 -0.248)
      (stroke (width 0.15) (type solid)) (layer "B.Fab"))
    (fp_line (start 0.504 0.25) (end 0.504 -0.248)
      (stroke (width 0.15) (type solid)) (layer "B.Fab"))
    (pad "1" smd roundrect (at -0.48 0 90) (size 0.59 0.64) (layers "B.Cu" "B.Paste" "B.Mask") (roundrect_rratio 0.25)
      (net 1 "GND") (pintype "passive"))
    (pad "2" smd roundrect (at 0.48 0 90) (size 0.59 0.64) (layers "B.Cu" "B.Paste" "B.Mask") (roundrect_rratio 0.25)
      (net 657 "VREGOUT") (pintype "passive"))
  )
	(footprint "antmicro-footprints:C_0402_1005Metric" (layer "B.Cu")
    (at 131.9 88.525 90)
    (descr "Capacitor SMD 0402")
    (tags "capacitor SMD 0402")
    (property "Author" "Antmicro")
    (property "Dielectric" "X5R")
    (property "License" "Apache-2.0")
    (property "MPN" "GRM155R61H104KE14D")
    (property "Manufacturer" "Murata")
    (property "Public" "False")
    (property "Sheetfile" "interfaces.kicad_sch")
    (property "Sheetname" "Interfaces")
    (property "Val" "100n")
    (property "Voltage" "50V")
    (property "ki_description" "SMD Multilayer Ceramic Capacitor, 0.1 µF, 50 V, 0402 [1005 Metric], ± 10%, X5R, GRM Series")
    (property "ki_keywords" "0402, SMT, CAPACITOR, PASSIVE, CERAMIC, MLCC")
    (attr smd)
    (fp_text reference "C253" (at -0.06 -1.06 90) (layer "B.SilkS")
        (effects (font (size 0.7 0.7) (thickness 0.15)) (justify mirror))
    )
    (fp_text value "C_100n_0402" (at 0 -1.17 90) (layer "B.Fab")
        (effects (font (size 1 1) (thickness 0.15)) (justify mirror))
    )
    (fp_text user "${REFERENCE}" (at 0 0 90) (layer "B.Fab")
        (effects (font (size 0.25 0.25) (thickness 0.04)) (justify mirror))
    )
    (fp_text user "License: Apache-2.0" (at -0.939 -5.799 270) (layer "B.Fab") hide
        (effects (font (size 0.7 0.7) (thickness 0.15)) (justify left bottom mirror))
    )
    (fp_text user "Author: Antmicro" (at -0.939 -3.399 270) (layer "B.Fab") hide
        (effects (font (size 0.7 0.7) (thickness 0.15)) (justify left bottom mirror))
    )
    (fp_rect (start -0.925 0.47) (end 0.925 -0.47)
      (stroke (width 0.05) (type default)) (fill none) (layer "B.CrtYd"))
    (fp_line (start -0.494 -0.248) (end -0.494 0.25)
      (stroke (width 0.15) (type solid)) (layer "B.Fab"))
    (fp_line (start -0.494 0.25) (end 0.504 0.25)
      (stroke (width 0.15) (type solid)) (layer "B.Fab"))
    (fp_line (start 0.504 -0.248) (end -0.494 -0.248)
      (stroke (width 0.15) (type solid)) (layer "B.Fab"))
    (fp_line (start 0.504 0.25) (end 0.504 -0.248)
      (stroke (width 0.15) (type solid)) (layer "B.Fab"))
    (pad "1" smd roundrect (at -0.48 0 90) (size 0.59 0.64) (layers "B.Cu" "B.Paste" "B.Mask") (roundrect_rratio 0.25)
      (net 1 "GND") (pintype "passive"))
    (pad "2" smd roundrect (at 0.48 0 90) (size 0.59 0.64) (layers "B.Cu" "B.Paste" "B.Mask") (roundrect_rratio 0.25)
      (net 2 "VCC3V3") (pintype "passive"))
  )
	(footprint "antmicro-footprints:C_0402_1005Metric" (layer "B.Cu")
    (at 140.415 92.525)
    (descr "Capacitor SMD 0402")
    (tags "capacitor SMD 0402")
    (property "Author" "Antmicro")
    (property "Dielectric" "X5R")
    (property "License" "Apache-2.0")
    (property "MPN" "GRM155R61H104KE14D")
    (property "Manufacturer" "Murata")
    (property "Public" "False")
    (property "Sheetfile" "interfaces.kicad_sch")
    (property "Sheetname" "Interfaces")
    (property "Val" "100n")
    (property "Voltage" "50V")
    (property "ki_description" "SMD Multilayer Ceramic Capacitor, 0.1 µF, 50 V, 0402 [1005 Metric], ± 10%, X5R, GRM Series")
    (property "ki_keywords" "0402, SMT, CAPACITOR, PASSIVE, CERAMIC, MLCC")
    (attr smd)
    (fp_text reference "C258" (at 2.765 -0.11) (layer "B.SilkS")
        (effects (font (size 0.7 0.7) (thickness 0.15)) (justify mirror))
    )
    (fp_text value "C_100n_0402" (at 0 -1.17) (layer "B.Fab")
        (effects (font (size 1 1) (thickness 0.15)) (justify mirror))
    )
    (fp_text user "Author: Antmicro" (at -0.939 -3.399 180) (layer "B.Fab") hide
        (effects (font (size 0.7 0.7) (thickness 0.15)) (justify left bottom mirror))
    )
    (fp_text user "License: Apache-2.0" (at -0.939 -5.799 180) (layer "B.Fab") hide
        (effects (font (size 0.7 0.7) (thickness 0.15)) (justify left bottom mirror))
    )
    (fp_text user "${REFERENCE}" (at 0 0) (layer "B.Fab")
        (effects (font (size 0.25 0.25) (thickness 0.04)) (justify mirror))
    )
    (fp_rect (start -0.925 0.47) (end 0.925 -0.47)
      (stroke (width 0.05) (type default)) (fill none) (layer "B.CrtYd"))
    (fp_line (start -0.494 -0.248) (end -0.494 0.25)
      (stroke (width 0.15) (type solid)) (layer "B.Fab"))
    (fp_line (start -0.494 0.25) (end 0.504 0.25)
      (stroke (width 0.15) (type solid)) (layer "B.Fab"))
    (fp_line (start 0.504 -0.248) (end -0.494 -0.248)
      (stroke (width 0.15) (type solid)) (layer "B.Fab"))
    (fp_line (start 0.504 0.25) (end 0.504 -0.248)
      (stroke (width 0.15) (type solid)) (layer "B.Fab"))
    (pad "1" smd roundrect (at -0.48 0) (size 0.59 0.64) (layers "B.Cu" "B.Paste" "B.Mask") (roundrect_rratio 0.25)
      (net 1 "GND") (pintype "passive"))
    (pad "2" smd roundrect (at 0.48 0) (size 0.59 0.64) (layers "B.Cu" "B.Paste" "B.Mask") (roundrect_rratio 0.25)
      (net 2 "VCC3V3") (pintype "passive"))
  )
	(footprint "antmicro-footprints:C_0402_1005Metric" (layer "B.Cu")
    (at 139.1 86.325 90)
    (descr "Capacitor SMD 0402")
    (tags "capacitor SMD 0402")
    (property "Author" "Antmicro")
    (property "Dielectric" "")
    (property "License" "Apache-2.0")
    (property "MPN" "GRM155R61A475MEAAD")
    (property "Manufacturer" "Murata")
    (property "Public" "False")
    (property "Sheetfile" "interfaces.kicad_sch")
    (property "Sheetname" "Interfaces")
    (property "Val" "4u7")
    (property "Voltage" "")
    (property "ki_description" "SMD Multilayer Ceramic Capacitor, 4.7 µF, 10 V, 0402 [1005 Metric], ± 20%, X5R, GRM Series")
    (property "ki_keywords" "0402, SMT, CAPACITOR, PASSIVE")
    (attr smd)
    (fp_text reference "C252" (at -2.96 -0.05 90) (layer "B.SilkS")
        (effects (font (size 0.7 0.7) (thickness 0.15)) (justify mirror))
    )
    (fp_text value "C_4u7_0402" (at 0 -1.17 90) (layer "B.Fab")
        (effects (font (size 1 1) (thickness 0.15)) (justify mirror))
    )
    (fp_text user "${REFERENCE}" (at 0 0 90) (layer "B.Fab")
        (effects (font (size 0.25 0.25) (thickness 0.04)) (justify mirror))
    )
    (fp_text user "Author: Antmicro" (at -0.939 -3.399 270) (layer "B.Fab") hide
        (effects (font (size 0.7 0.7) (thickness 0.15)) (justify left bottom mirror))
    )
    (fp_text user "License: Apache-2.0" (at -0.939 -5.799 270) (layer "B.Fab") hide
        (effects (font (size 0.7 0.7) (thickness 0.15)) (justify left bottom mirror))
    )
    (fp_rect (start -0.925 0.47) (end 0.925 -0.47)
      (stroke (width 0.05) (type default)) (fill none) (layer "B.CrtYd"))
    (fp_line (start -0.494 -0.248) (end -0.494 0.25)
      (stroke (width 0.15) (type solid)) (layer "B.Fab"))
    (fp_line (start -0.494 0.25) (end 0.504 0.25)
      (stroke (width 0.15) (type solid)) (layer "B.Fab"))
    (fp_line (start 0.504 -0.248) (end -0.494 -0.248)
      (stroke (width 0.15) (type solid)) (layer "B.Fab"))
    (fp_line (start 0.504 0.25) (end 0.504 -0.248)
      (stroke (width 0.15) (type solid)) (layer "B.Fab"))
    (pad "1" smd roundrect (at -0.48 0 90) (size 0.59 0.64) (layers "B.Cu" "B.Paste" "B.Mask") (roundrect_rratio 0.25)
      (net 1 "GND") (pintype "passive"))
    (pad "2" smd roundrect (at 0.48 0 90) (size 0.59 0.64) (layers "B.Cu" "B.Paste" "B.Mask") (roundrect_rratio 0.25)
      (net 307 "Net-(U14-V_{PHY})") (pintype "passive"))
  )
)
